(kicad_pcb
	(version 20260206)
	(generator "pcbnew")
	(generator_version "10.0")
	(general
		(thickness 1.6)
		(legacy_teardrops no)
	)
	(paper "A4")
	(title_block
		(title "Wiwynn_Tioga_Pass_MB.brd")
		(comment 1 "Tioga Pass / footprints 2860-2867 of 4770")
	)
	(layers
		(0 "F.Cu" signal "TOP")
		(4 "In1.Cu" signal "L2GND")
		(6 "In2.Cu" signal "L3")
		(8 "In3.Cu" signal "L4GND")
		(10 "In4.Cu" signal "L5")
		(12 "In5.Cu" signal "L6GND")
		(14 "In6.Cu" signal "L7VCC")
		(16 "In7.Cu" signal "L8VCC")
		(18 "In8.Cu" signal "L9GND")
		(20 "In9.Cu" signal "L10")
		(22 "In10.Cu" signal "L11GND")
		(24 "In11.Cu" signal "L12")
		(26 "In12.Cu" signal "L13GND")
		(2 "B.Cu" signal "BOTTOM")
		(9 "F.Adhes" user "F.Adhesive")
		(11 "B.Adhes" user "B.Adhesive")
		(13 "F.Paste" user "Package Geometry/Pastemask Top")
		(15 "B.Paste" user "Package Geometry/Pastemask Bottom")
		(5 "F.SilkS" user "Ref Des/Silkscreen Top")
		(7 "B.SilkS" user "Ref Des/Silkscreen Bottom")
		(1 "F.Mask" user "Board Geometry/Soldermask Top")
		(3 "B.Mask" user "Board Geometry/Soldermask Bottom")
		(17 "Dwgs.User" user "User.Drawings")
		(19 "Cmts.User" user "User.Comments")
		(21 "Eco1.User" user "User.Eco1")
		(23 "Eco2.User" user "User.Eco2")
		(25 "Edge.Cuts" user "Board Geometry/Outline")
		(27 "Margin" user)
		(31 "F.CrtYd" user "Package Geometry/Place Bound Top")
		(29 "B.CrtYd" user "Package Geometry/Place Bound Bottom")
		(35 "F.Fab" user "Ref Des/Assembly Top")
		(33 "B.Fab" user "Ref Des/Assembly Bottom")
	)
	(footprint ""
		(layer "B.Cu")
		(at 422.70172 -149.987 90)
		(property "Reference" "C2L17"
			(at 0 0 90)
			(layer "B.SilkS")
			(hide yes)
			(effects
				(font
					(size 1.27 1.27)
				)
				(justify mirror)
			)
		)
		(property "Value" ""
			(at 0 0 90)
			(layer "B.Fab")
			(effects
				(font
					(size 1.27 1.27)
				)
				(justify mirror)
			)
		)
		(duplicate_pad_numbers_are_jumpers no)
		(fp_poly
			(pts
				(xy -0.3048 -0.1016) (xy -0.3048 0.9906) (xy 0.3048 0.9906) (xy 0.3048 -0.1016)
			)
			(stroke
				(width 0)
				(type default)
			)
			(fill no)
			(layer "B.CrtYd")
		)
		(fp_line
			(start 0.3048 -0.1016)
			(end 0.3048 0.9906)
			(stroke
				(width 0.1)
				(type default)
			)
			(layer "B.Fab")
		)
		(fp_line
			(start -0.3048 -0.1016)
			(end 0.3048 -0.1016)
			(stroke
				(width 0.1)
				(type default)
			)
			(layer "B.Fab")
		)
		(fp_line
			(start 0.3048 0.9906)
			(end -0.3048 0.9906)
			(stroke
				(width 0.1)
				(type default)
			)
			(layer "B.Fab")
		)
		(fp_line
			(start -0.3048 0.9906)
			(end -0.3048 -0.1016)
			(stroke
				(width 0.1)
				(type default)
			)
			(layer "B.Fab")
		)
		(pad "1" smd rect
			(at 0 0 270)
			(size 0.508 0.508)
			(layers "B.Cu" "B.Mask" "B.Paste")
			(net "SATA6G_PCH_PCIE_UP_SATA_RXN<0>")
		)
		(pad "2" smd rect
			(at 0 0.889 270)
			(size 0.508 0.508)
			(layers "B.Cu" "B.Mask" "B.Paste")
			(net "SATA6G_P0_RX_C_DN")
		)
		(zone
			(layer "B.Cu")
			(hatch none 0.5)
			(connect_pads
				(clearance 0)
			)
			(min_thickness 0.25)
			(keepout
				(tracks allowed)
				(vias not_allowed)
				(pads allowed)
				(copperpour not_allowed)
				(footprints allowed)
			)
			(placement
				(enabled no)
				(sheetname "")
			)
			(fill
				(thermal_gap 0.5)
				(thermal_bridge_width 0.5)
				(island_removal_mode 0)
			)
			(polygon
				(pts
					(xy 422.95572 -150.241) (xy 422.95572 -149.733) (xy 423.33672 -149.733) (xy 423.33672 -150.241)
				)
			)
		)
		(zone
			(layer "B.Cu")
			(hatch none 0.5)
			(connect_pads
				(clearance 0)
			)
			(min_thickness 0.25)
			(keepout
				(tracks not_allowed)
				(vias allowed)
				(pads allowed)
				(copperpour not_allowed)
				(footprints allowed)
			)
			(placement
				(enabled no)
				(sheetname "")
			)
			(fill
				(thermal_gap 0.5)
				(thermal_bridge_width 0.5)
				(island_removal_mode 0)
			)
			(polygon
				(pts
					(xy 423.33672 -150.241) (xy 423.33672 -149.733) (xy 422.95572 -149.733) (xy 422.95572 -150.241)
				)
			)
		)
	)
	(footprint ""
		(layer "B.Cu")
		(at 486.300526 -55.853584)
		(property "Reference" "C30W9"
			(at 0 0 0)
			(layer "B.SilkS")
			(hide yes)
			(effects
				(font
					(size 1.27 1.27)
				)
				(justify mirror)
			)
		)
		(property "Value" "*"
			(at 0.0762 -6.2357 0)
			(unlocked yes)
			(layer "B.Fab")
			(hide yes)
			(effects
				(font
					(size 1.27 1.016)
					(thickness 0.1524)
				)
				(justify mirror)
			)
		)
		(property "Device Type" "SC22U16V5MX-4-GP_SMD-BCG5-SC22A"
			(at 0.0762 -8.2677 0)
			(unlocked yes)
			(layer "B.Fab")
			(hide yes)
			(effects
				(font
					(size 1.27 1.016)
					(thickness 0.1524)
				)
				(justify mirror)
			)
		)
		(duplicate_pad_numbers_are_jumpers no)
		(fp_line
			(start -0.635 0)
			(end 0.635 0)
			(stroke
				(width 0.508)
				(type default)
			)
			(layer "B.SilkS")
		)
		(fp_rect
			(start 0.9652 1.778)
			(end -0.9652 -1.778)
			(stroke
				(width 0)
				(type default)
			)
			(fill no)
			(layer "B.CrtYd")
		)
		(fp_poly
			(pts
				(xy 0.9652 -1.778) (xy -0.9652 -1.778) (xy -0.9652 1.778) (xy 0.9652 1.778)
			)
			(stroke
				(width 0)
				(type default)
			)
			(fill no)
			(layer "B.Fab")
		)
		(pad "1" smd rect
			(at 0 -0.9652 180)
			(size 1.397 1.143)
			(layers "B.Cu" "B.Mask" "B.Paste")
			(net "P5V_STBY_USBC")
		)
		(pad "2" smd rect
			(at 0 0.9652 180)
			(size 1.397 1.143)
			(layers "B.Cu" "B.Mask" "B.Paste")
			(net "GND")
		)
	)
	(footprint ""
		(layer "B.Cu")
		(at 162.7886 -79.248 90)
		(property "Reference" "R7P7"
			(at 0 0 90)
			(layer "B.SilkS")
			(hide yes)
			(effects
				(font
					(size 1.27 1.27)
				)
				(justify mirror)
			)
		)
		(property "Value" ""
			(at 0 0 90)
			(layer "B.Fab")
			(effects
				(font
					(size 1.27 1.27)
				)
				(justify mirror)
			)
		)
		(duplicate_pad_numbers_are_jumpers no)
		(fp_poly
			(pts
				(xy 0.2794 -0.1016) (xy -0.2794 -0.1016) (xy -0.2794 0.9906) (xy 0.2794 0.9906)
			)
			(stroke
				(width 0)
				(type default)
			)
			(fill no)
			(layer "B.CrtYd")
		)
		(fp_line
			(start 0.2794 -0.1016)
			(end 0.2794 0.9906)
			(stroke
				(width 0.1)
				(type default)
			)
			(layer "B.Fab")
		)
		(fp_line
			(start -0.2794 -0.1016)
			(end 0.2794 -0.1016)
			(stroke
				(width 0.1)
				(type default)
			)
			(layer "B.Fab")
		)
		(fp_line
			(start 0.2794 0.9906)
			(end -0.2794 0.9906)
			(stroke
				(width 0.1)
				(type default)
			)
			(layer "B.Fab")
		)
		(fp_line
			(start -0.2794 0.9906)
			(end -0.2794 -0.1016)
			(stroke
				(width 0.1)
				(type default)
			)
			(layer "B.Fab")
		)
		(pad "1" smd rect
			(at 0 0 270)
			(size 0.508 0.508)
			(layers "B.Cu" "B.Mask" "B.Paste")
			(net "CLK_100M_CPU1_RC_REFCLK0_DN")
		)
		(pad "2" smd rect
			(at 0 0.889 270)
			(size 0.508 0.508)
			(layers "B.Cu" "B.Mask" "B.Paste")
			(net "GND")
		)
		(zone
			(layer "B.Cu")
			(hatch none 0.5)
			(connect_pads
				(clearance 0)
			)
			(min_thickness 0.25)
			(keepout
				(tracks allowed)
				(vias not_allowed)
				(pads allowed)
				(copperpour not_allowed)
				(footprints allowed)
			)
			(placement
				(enabled no)
				(sheetname "")
			)
			(fill
				(thermal_gap 0.5)
				(thermal_bridge_width 0.5)
				(island_removal_mode 0)
			)
			(polygon
				(pts
					(xy 163.0426 -79.502) (xy 163.0426 -78.994) (xy 163.4236 -78.994) (xy 163.4236 -79.502)
				)
			)
		)
		(zone
			(layer "B.Cu")
			(hatch none 0.5)
			(connect_pads
				(clearance 0)
			)
			(min_thickness 0.25)
			(keepout
				(tracks not_allowed)
				(vias allowed)
				(pads allowed)
				(copperpour not_allowed)
				(footprints allowed)
			)
			(placement
				(enabled no)
				(sheetname "")
			)
			(fill
				(thermal_gap 0.5)
				(thermal_bridge_width 0.5)
				(island_removal_mode 0)
			)
			(polygon
				(pts
					(xy 163.4236 -79.502) (xy 163.4236 -78.994) (xy 163.0426 -78.994) (xy 163.0426 -79.502)
				)
			)
		)
	)
	(footprint ""
		(layer "B.Cu")
		(at 12.40282 -101.57968 90)
		(property "Reference" "C9N10"
			(at 0 0 90)
			(layer "B.SilkS")
			(hide yes)
			(effects
				(font
					(size 1.27 1.27)
				)
				(justify mirror)
			)
		)
		(property "Value" ""
			(at 0 0 90)
			(layer "B.Fab")
			(effects
				(font
					(size 1.27 1.27)
				)
				(justify mirror)
			)
		)
		(duplicate_pad_numbers_are_jumpers no)
		(fp_poly
			(pts
				(xy -0.3048 -0.1016) (xy -0.3048 0.9906) (xy 0.3048 0.9906) (xy 0.3048 -0.1016)
			)
			(stroke
				(width 0)
				(type default)
			)
			(fill no)
			(layer "B.CrtYd")
		)
		(fp_line
			(start 0.3048 -0.1016)
			(end 0.3048 0.9906)
			(stroke
				(width 0.1)
				(type default)
			)
			(layer "B.Fab")
		)
		(fp_line
			(start -0.3048 -0.1016)
			(end 0.3048 -0.1016)
			(stroke
				(width 0.1)
				(type default)
			)
			(layer "B.Fab")
		)
		(fp_line
			(start 0.3048 0.9906)
			(end -0.3048 0.9906)
			(stroke
				(width 0.1)
				(type default)
			)
			(layer "B.Fab")
		)
		(fp_line
			(start -0.3048 0.9906)
			(end -0.3048 -0.1016)
			(stroke
				(width 0.1)
				(type default)
			)
			(layer "B.Fab")
		)
		(pad "1" smd rect
			(at 0 0 270)
			(size 0.508 0.508)
			(layers "B.Cu" "B.Mask" "B.Paste")
			(net "P3E_CPU1_PE3_MP_C_TXP<14>")
		)
		(pad "2" smd rect
			(at 0 0.889 270)
			(size 0.508 0.508)
			(layers "B.Cu" "B.Mask" "B.Paste")
			(net "P3E_CPU1_PE3_MP_TXP<14>")
		)
		(zone
			(layer "B.Cu")
			(hatch none 0.5)
			(connect_pads
				(clearance 0)
			)
			(min_thickness 0.25)
			(keepout
				(tracks allowed)
				(vias not_allowed)
				(pads allowed)
				(copperpour not_allowed)
				(footprints allowed)
			)
			(placement
				(enabled no)
				(sheetname "")
			)
			(fill
				(thermal_gap 0.5)
				(thermal_bridge_width 0.5)
				(island_removal_mode 0)
			)
			(polygon
				(pts
					(xy 12.65682 -101.83368) (xy 12.65682 -101.32568) (xy 13.03782 -101.32568) (xy 13.03782 -101.83368)
				)
			)
		)
		(zone
			(layer "B.Cu")
			(hatch none 0.5)
			(connect_pads
				(clearance 0)
			)
			(min_thickness 0.25)
			(keepout
				(tracks not_allowed)
				(vias allowed)
				(pads allowed)
				(copperpour not_allowed)
				(footprints allowed)
			)
			(placement
				(enabled no)
				(sheetname "")
			)
			(fill
				(thermal_gap 0.5)
				(thermal_bridge_width 0.5)
				(island_removal_mode 0)
			)
			(polygon
				(pts
					(xy 13.03782 -101.83368) (xy 13.03782 -101.32568) (xy 12.65682 -101.32568) (xy 12.65682 -101.83368)
				)
			)
		)
	)
	(footprint ""
		(layer "B.Cu")
		(at 418.719 -9.017 -90)
		(property "Reference" "R3P48"
			(at 0 0 90)
			(layer "B.SilkS")
			(hide yes)
			(effects
				(font
					(size 1.27 1.27)
				)
				(justify mirror)
			)
		)
		(property "Value" ""
			(at 0 0 90)
			(layer "B.Fab")
			(effects
				(font
					(size 1.27 1.27)
				)
				(justify mirror)
			)
		)
		(duplicate_pad_numbers_are_jumpers no)
		(fp_rect
			(start -0.2794 0.9906)
			(end 0.2794 -0.1016)
			(stroke
				(width 0)
				(type default)
			)
			(fill no)
			(layer "B.CrtYd")
		)
		(fp_line
			(start -0.2794 0.9906)
			(end -0.2794 -0.1016)
			(stroke
				(width 0.1)
				(type default)
			)
			(layer "B.Fab")
		)
		(fp_line
			(start 0.2794 0.9906)
			(end -0.2794 0.9906)
			(stroke
				(width 0.1)
				(type default)
			)
			(layer "B.Fab")
		)
		(fp_line
			(start -0.2794 -0.1016)
			(end 0.2794 -0.1016)
			(stroke
				(width 0.1)
				(type default)
			)
			(layer "B.Fab")
		)
		(fp_line
			(start 0.2794 -0.1016)
			(end 0.2794 0.9906)
			(stroke
				(width 0.1)
				(type default)
			)
			(layer "B.Fab")
		)
		(pad "1" smd rect
			(at 0 0 90)
			(size 0.508 0.508)
			(layers "B.Cu" "B.Mask" "B.Paste")
			(net "P12V_STBY")
		)
		(pad "2" smd rect
			(at 0 0.889 90)
			(size 0.508 0.508)
			(layers "B.Cu" "B.Mask" "B.Paste")
			(net "VSENSE_P12V_ADM1085")
		)
		(zone
			(layer "B.Cu")
			(hatch none 0.5)
			(connect_pads
				(clearance 0)
			)
			(min_thickness 0.25)
			(keepout
				(tracks allowed)
				(vias not_allowed)
				(pads allowed)
				(copperpour not_allowed)
				(footprints allowed)
			)
			(placement
				(enabled no)
				(sheetname "")
			)
			(fill
				(thermal_gap 0.5)
				(thermal_bridge_width 0.5)
				(island_removal_mode 0)
			)
			(polygon
				(pts
					(xy 418.084 -9.271) (xy 418.084 -8.763) (xy 418.465 -8.763) (xy 418.465 -9.271)
				)
			)
		)
		(zone
			(layer "B.Cu")
			(hatch none 0.5)
			(connect_pads
				(clearance 0)
			)
			(min_thickness 0.25)
			(keepout
				(tracks not_allowed)
				(vias allowed)
				(pads allowed)
				(copperpour not_allowed)
				(footprints allowed)
			)
			(placement
				(enabled no)
				(sheetname "")
			)
			(fill
				(thermal_gap 0.5)
				(thermal_bridge_width 0.5)
				(island_removal_mode 0)
			)
			(polygon
				(pts
					(xy 418.084 -9.271) (xy 418.084 -8.763) (xy 418.465 -8.763) (xy 418.465 -9.271)
				)
			)
		)
	)
	(footprint ""
		(layer "B.Cu")
		(at 475.412816 -145.470372 180)
		(property "Reference" "R6W11"
			(at 0.8382 -0.67818 180)
			(unlocked yes)
			(layer "B.SilkS")
			(effects
				(font
					(size 0.4064 0.254)
					(thickness 0.1524)
				)
				(justify left mirror)
			)
		)
		(property "Value" ""
			(at 0 0 0)
			(layer "B.Fab")
			(effects
				(font
					(size 1.27 1.27)
				)
				(justify mirror)
			)
		)
		(duplicate_pad_numbers_are_jumpers no)
		(fp_poly
			(pts
				(xy 0.2794 -0.1016) (xy -0.2794 -0.1016) (xy -0.2794 0.9906) (xy 0.2794 0.9906)
			)
			(stroke
				(width 0)
				(type default)
			)
			(fill no)
			(layer "B.CrtYd")
		)
		(fp_line
			(start 0.2794 0.9906)
			(end -0.2794 0.9906)
			(stroke
				(width 0.1)
				(type default)
			)
			(layer "B.Fab")
		)
		(fp_line
			(start 0.2794 -0.1016)
			(end 0.2794 0.9906)
			(stroke
				(width 0.1)
				(type default)
			)
			(layer "B.Fab")
		)
		(fp_line
			(start -0.2794 0.9906)
			(end -0.2794 -0.1016)
			(stroke
				(width 0.1)
				(type default)
			)
			(layer "B.Fab")
		)
		(fp_line
			(start -0.2794 -0.1016)
			(end 0.2794 -0.1016)
			(stroke
				(width 0.1)
				(type default)
			)
			(layer "B.Fab")
		)
		(pad "1" smd rect
			(at 0 0)
			(size 0.508 0.508)
			(layers "B.Cu" "B.Mask" "B.Paste")
			(net "SMB_DEBUG_STBY_LVC3_SCL")
		)
		(pad "2" smd rect
			(at 0 0.889)
			(size 0.508 0.508)
			(layers "B.Cu" "B.Mask" "B.Paste")
			(net "P3V3_STBY")
		)
		(zone
			(layer "B.Cu")
			(hatch none 0.5)
			(connect_pads
				(clearance 0)
			)
			(min_thickness 0.25)
			(keepout
				(tracks not_allowed)
				(vias allowed)
				(pads allowed)
				(copperpour not_allowed)
				(footprints allowed)
			)
			(placement
				(enabled no)
				(sheetname "")
			)
			(fill
				(thermal_gap 0.5)
				(thermal_bridge_width 0.5)
				(island_removal_mode 0)
			)
			(polygon
				(pts
					(xy 475.158816 -146.105372) (xy 475.666816 -146.105372) (xy 475.666816 -145.724372) (xy 475.158816 -145.724372)
				)
			)
		)
		(zone
			(layer "B.Cu")
			(hatch none 0.5)
			(connect_pads
				(clearance 0)
			)
			(min_thickness 0.25)
			(keepout
				(tracks allowed)
				(vias not_allowed)
				(pads allowed)
				(copperpour not_allowed)
				(footprints allowed)
			)
			(placement
				(enabled no)
				(sheetname "")
			)
			(fill
				(thermal_gap 0.5)
				(thermal_bridge_width 0.5)
				(island_removal_mode 0)
			)
			(polygon
				(pts
					(xy 475.158816 -145.724372) (xy 475.666816 -145.724372) (xy 475.666816 -146.105372) (xy 475.158816 -146.105372)
				)
			)
		)
	)
	(footprint ""
		(layer "B.Cu")
		(at 429.046894 -15.280894 -90)
		(property "Reference" "R1U57"
			(at 0 0 90)
			(layer "B.SilkS")
			(hide yes)
			(effects
				(font
					(size 1.27 1.27)
				)
				(justify mirror)
			)
		)
		(property "Value" ""
			(at 0 0 90)
			(layer "B.Fab")
			(effects
				(font
					(size 1.27 1.27)
				)
				(justify mirror)
			)
		)
		(duplicate_pad_numbers_are_jumpers no)
		(fp_poly
			(pts
				(xy 0.2794 -0.1016) (xy -0.2794 -0.1016) (xy -0.2794 0.9906) (xy 0.2794 0.9906)
			)
			(stroke
				(width 0)
				(type default)
			)
			(fill no)
			(layer "B.CrtYd")
		)
		(fp_line
			(start -0.2794 0.9906)
			(end -0.2794 -0.1016)
			(stroke
				(width 0.1)
				(type default)
			)
			(layer "B.Fab")
		)
		(fp_line
			(start 0.2794 0.9906)
			(end -0.2794 0.9906)
			(stroke
				(width 0.1)
				(type default)
			)
			(layer "B.Fab")
		)
		(fp_line
			(start -0.2794 -0.1016)
			(end 0.2794 -0.1016)
			(stroke
				(width 0.1)
				(type default)
			)
			(layer "B.Fab")
		)
		(fp_line
			(start 0.2794 -0.1016)
			(end 0.2794 0.9906)
			(stroke
				(width 0.1)
				(type default)
			)
			(layer "B.Fab")
		)
		(pad "1" smd rect
			(at 0 0 90)
			(size 0.508 0.508)
			(layers "B.Cu" "B.Mask" "B.Paste")
			(net "H_CPU1_MEMGHJ_MEMHOT_LVT3_K_N")
		)
		(pad "2" smd rect
			(at 0 0.889 90)
			(size 0.508 0.508)
			(layers "B.Cu" "B.Mask" "B.Paste")
			(net "H_CPU1_MEMGHJ_MEMHOT_G_PCH_N")
		)
		(zone
			(layer "B.Cu")
			(hatch none 0.5)
			(connect_pads
				(clearance 0)
			)
			(min_thickness 0.25)
			(keepout
				(tracks not_allowed)
				(vias allowed)
				(pads allowed)
				(copperpour not_allowed)
				(footprints allowed)
			)
			(placement
				(enabled no)
				(sheetname "")
			)
			(fill
				(thermal_gap 0.5)
				(thermal_bridge_width 0.5)
				(island_removal_mode 0)
			)
			(polygon
				(pts
					(xy 428.411894 -15.026894) (xy 428.411894 -15.534894) (xy 428.792894 -15.534894) (xy 428.792894 -15.026894)
				)
			)
		)
		(zone
			(layer "B.Cu")
			(hatch none 0.5)
			(connect_pads
				(clearance 0)
			)
			(min_thickness 0.25)
			(keepout
				(tracks allowed)
				(vias not_allowed)
				(pads allowed)
				(copperpour not_allowed)
				(footprints allowed)
			)
			(placement
				(enabled no)
				(sheetname "")
			)
			(fill
				(thermal_gap 0.5)
				(thermal_bridge_width 0.5)
				(island_removal_mode 0)
			)
			(polygon
				(pts
					(xy 428.792894 -15.026894) (xy 428.792894 -15.534894) (xy 428.411894 -15.534894) (xy 428.411894 -15.026894)
				)
			)
		)
	)
	(footprint ""
		(layer "B.Cu")
		(at 448.2846 -129.3622 180)
		(property "Reference" "C1M35"
			(at 0 0 0)
			(layer "B.SilkS")
			(hide yes)
			(effects
				(font
					(size 1.27 1.27)
				)
				(justify mirror)
			)
		)
		(property "Value" ""
			(at 0 0 0)
			(layer "B.Fab")
			(effects
				(font
					(size 1.27 1.27)
				)
				(justify mirror)
			)
		)
		(duplicate_pad_numbers_are_jumpers no)
		(fp_poly
			(pts
				(xy -0.3048 -0.1016) (xy -0.3048 0.9906) (xy 0.3048 0.9906) (xy 0.3048 -0.1016)
			)
			(stroke
				(width 0)
				(type default)
			)
			(fill no)
			(layer "B.CrtYd")
		)
		(fp_line
			(start 0.3048 0.9906)
			(end -0.3048 0.9906)
			(stroke
				(width 0.1)
				(type default)
			)
			(layer "B.Fab")
		)
		(fp_line
			(start 0.3048 -0.1016)
			(end 0.3048 0.9906)
			(stroke
				(width 0.1)
				(type default)
			)
			(layer "B.Fab")
		)
		(fp_line
			(start -0.3048 0.9906)
			(end -0.3048 -0.1016)
			(stroke
				(width 0.1)
				(type default)
			)
			(layer "B.Fab")
		)
		(fp_line
			(start -0.3048 -0.1016)
			(end 0.3048 -0.1016)
			(stroke
				(width 0.1)
				(type default)
			)
			(layer "B.Fab")
		)
		(pad "1" smd rect
			(at 0 0)
			(size 0.508 0.508)
			(layers "B.Cu" "B.Mask" "B.Paste")
			(net "P3V3_STBY")
		)
		(pad "2" smd rect
			(at 0 0.889)
			(size 0.508 0.508)
			(layers "B.Cu" "B.Mask" "B.Paste")
			(net "GND")
		)
		(zone
			(layer "B.Cu")
			(hatch none 0.5)
			(connect_pads
				(clearance 0)
			)
			(min_thickness 0.25)
			(keepout
				(tracks not_allowed)
				(vias allowed)
				(pads allowed)
				(copperpour not_allowed)
				(footprints allowed)
			)
			(placement
				(enabled no)
				(sheetname "")
			)
			(fill
				(thermal_gap 0.5)
				(thermal_bridge_width 0.5)
				(island_removal_mode 0)
			)
			(polygon
				(pts
					(xy 448.0306 -129.9972) (xy 448.5386 -129.9972) (xy 448.5386 -129.6162) (xy 448.0306 -129.6162)
				)
			)
		)
		(zone
			(layer "B.Cu")
			(hatch none 0.5)
			(connect_pads
				(clearance 0)
			)
			(min_thickness 0.25)
			(keepout
				(tracks allowed)
				(vias not_allowed)
				(pads allowed)
				(copperpour not_allowed)
				(footprints allowed)
			)
			(placement
				(enabled no)
				(sheetname "")
			)
			(fill
				(thermal_gap 0.5)
				(thermal_bridge_width 0.5)
				(island_removal_mode 0)
			)
			(polygon
				(pts
					(xy 448.0306 -129.6162) (xy 448.5386 -129.6162) (xy 448.5386 -129.9972) (xy 448.0306 -129.9972)
				)
			)
		)
	)
)
